(kicad_pcb
	(version 20260206)
	(generator "pcbnew")
	(generator_version "10.0")
	(general
		(thickness 1.6)
		(legacy_teardrops no)
	)
	(paper "A4")
	(title_block
		(title "v1-chassis-manager — T6M_CM_d_v01_1031_1645.brd")
		(comment 1 "Open CloudServer (Microsoft) / footprints 2013-2022 of 2512")
	)
	(layers
		(0 "F.Cu" signal "TOP")
		(4 "In1.Cu" signal "GND1")
		(6 "In2.Cu" signal "IN1")
		(8 "In3.Cu" signal "VCC1")
		(10 "In4.Cu" signal "VCC2")
		(12 "In5.Cu" signal "GND2")
		(14 "In6.Cu" signal "IN2")
		(16 "In7.Cu" signal "IN3")
		(18 "In8.Cu" signal "GND3")
		(2 "B.Cu" signal "BOTTOM")
		(9 "F.Adhes" user "F.Adhesive")
		(11 "B.Adhes" user "B.Adhesive")
		(13 "F.Paste" user "Package Geometry/Pastemask Top")
		(15 "B.Paste" user "Package Geometry/Pastemask Bottom")
		(5 "F.SilkS" user "Ref Des/Silkscreen Top")
		(7 "B.SilkS" user "Ref Des/Silkscreen Bottom")
		(1 "F.Mask" user "Board Geometry/Soldermask Top")
		(3 "B.Mask" user "Board Geometry/Soldermask Bottom")
		(17 "Dwgs.User" user "User.Drawings")
		(19 "Cmts.User" user "User.Comments")
		(21 "Eco1.User" user "User.Eco1")
		(23 "Eco2.User" user "User.Eco2")
		(25 "Edge.Cuts" user "Board Geometry/Outline")
		(27 "Margin" user)
		(31 "F.CrtYd" user "Package Geometry/Place Bound Top")
		(29 "B.CrtYd" user "Package Geometry/Place Bound Bottom")
		(35 "F.Fab" user "Ref Des/Assembly Top")
		(33 "B.Fab" user "Ref Des/Assembly Bottom")
	)
	(footprint ""
		(layer "B.Cu")
		(at 165.998652 -104.87279 -90)
		(property "Reference" "C369"
			(at -1.398016 -6.444742 270)
			(unlocked yes)
			(layer "B.SilkS")
			(effects
				(font
					(size 0.7874 0.5842)
					(thickness 0.1524)
				)
				(justify left mirror)
			)
		)
		(property "Value" ""
			(at 0 0 90)
			(layer "B.Fab")
			(effects
				(font
					(size 1.27 1.27)
				)
				(justify mirror)
			)
		)
		(duplicate_pad_numbers_are_jumpers no)
		(fp_line
			(start -0.7874 0.4064)
			(end 0.7874 0.4064)
			(stroke
				(width 0.1524)
				(type default)
			)
			(layer "B.SilkS")
		)
		(fp_line
			(start 0.7874 0.4064)
			(end 0.7874 -0.4064)
			(stroke
				(width 0.1524)
				(type default)
			)
			(layer "B.SilkS")
		)
		(fp_line
			(start 0 0.381)
			(end 0 -0.381)
			(stroke
				(width 0.1524)
				(type default)
			)
			(layer "B.SilkS")
		)
		(fp_line
			(start -0.7874 -0.4064)
			(end -0.7874 0.4064)
			(stroke
				(width 0.1524)
				(type default)
			)
			(layer "B.SilkS")
		)
		(fp_line
			(start 0.7874 -0.4064)
			(end -0.7874 -0.4064)
			(stroke
				(width 0.1524)
				(type default)
			)
			(layer "B.SilkS")
		)
		(fp_poly
			(pts
				(xy 0.5334 0.254) (xy 0.635 0.254) (xy 0.635 0.2286) (xy 0.635 -0.254) (xy 0.5334 -0.254) (xy 0.5334 -0.2794)
				(xy -0.5334 -0.2794) (xy -0.5334 -0.254) (xy -0.635 -0.254) (xy -0.635 0.254) (xy -0.5334 0.254)
				(xy -0.5334 0.2794) (xy 0.508 0.2794) (xy 0.5334 0.2794)
			)
			(stroke
				(width 0)
				(type default)
			)
			(fill no)
			(layer "B.CrtYd")
		)
		(pad "1" smd rect
			(at -0.40005 0 90)
			(size 0.4572 0.508)
			(layers "B.Cu" "B.Mask" "B.Paste")
			(net "P1V05_NODE1")
		)
		(pad "2" smd rect
			(at 0.40005 0 90)
			(size 0.4572 0.508)
			(layers "B.Cu" "B.Mask" "B.Paste")
			(net "GND")
		)
	)
	(footprint ""
		(layer "B.Cu")
		(at 120.634252 -168.560242 180)
		(property "Reference" "R1244"
			(at -0.6858 2.08153 0)
			(unlocked yes)
			(layer "B.SilkS")
			(effects
				(font
					(size 0.7874 0.5842)
					(thickness 0.1524)
				)
				(justify left mirror)
			)
		)
		(property "Value" ""
			(at 0 0 0)
			(layer "B.Fab")
			(effects
				(font
					(size 1.27 1.27)
				)
				(justify mirror)
			)
		)
		(duplicate_pad_numbers_are_jumpers no)
		(fp_line
			(start 0.7874 0.4064)
			(end 0.7874 -0.4064)
			(stroke
				(width 0.1524)
				(type default)
			)
			(layer "B.SilkS")
		)
		(fp_line
			(start 0.7874 -0.4064)
			(end -0.7874 -0.4064)
			(stroke
				(width 0.1524)
				(type default)
			)
			(layer "B.SilkS")
		)
		(fp_line
			(start -0.7874 0.4064)
			(end 0.7874 0.4064)
			(stroke
				(width 0.1524)
				(type default)
			)
			(layer "B.SilkS")
		)
		(fp_line
			(start -0.7874 -0.4064)
			(end -0.7874 0.4064)
			(stroke
				(width 0.1524)
				(type default)
			)
			(layer "B.SilkS")
		)
		(fp_poly
			(pts
				(xy 0.508 0.2794) (xy 0.508 0.2286) (xy 0.635 0.2286) (xy 0.635 -0.254) (xy 0.5334 -0.254) (xy 0.5334 -0.2794)
				(xy -0.5334 -0.2794) (xy -0.5334 -0.254) (xy -0.635 -0.254) (xy -0.635 0.254) (xy -0.5334 0.254)
				(xy -0.5334 0.2794)
			)
			(stroke
				(width 0)
				(type default)
			)
			(fill no)
			(layer "B.CrtYd")
		)
		(pad "1" smd rect
			(at -0.40005 0)
			(size 0.4572 0.508)
			(layers "B.Cu" "B.Mask" "B.Paste")
			(net "GND")
		)
		(pad "2" smd rect
			(at 0.40005 0)
			(size 0.4572 0.508)
			(layers "B.Cu" "B.Mask" "B.Paste")
			(net "PSU2_HUB_EN")
		)
	)
	(footprint ""
		(layer "B.Cu")
		(at 33.72104 -104.873806 90)
		(property "Reference" "C820"
			(at 0.041402 -5.707888 270)
			(unlocked yes)
			(layer "B.SilkS")
			(effects
				(font
					(size 0.7874 0.5842)
					(thickness 0.1524)
				)
				(justify left mirror)
			)
		)
		(property "Value" ""
			(at 0 0 90)
			(layer "B.Fab")
			(effects
				(font
					(size 1.27 1.27)
				)
				(justify mirror)
			)
		)
		(duplicate_pad_numbers_are_jumpers no)
		(fp_line
			(start 1.905 -0.8636)
			(end -1.905 -0.8636)
			(stroke
				(width 0.1524)
				(type default)
			)
			(layer "B.SilkS")
		)
		(fp_line
			(start -1.905 -0.8636)
			(end -1.905 0.8636)
			(stroke
				(width 0.1524)
				(type default)
			)
			(layer "B.SilkS")
		)
		(fp_line
			(start 0 0.8382)
			(end 0 -0.8382)
			(stroke
				(width 0.1524)
				(type default)
			)
			(layer "B.SilkS")
		)
		(fp_line
			(start 1.905 0.8636)
			(end 1.905 -0.8636)
			(stroke
				(width 0.1524)
				(type default)
			)
			(layer "B.SilkS")
		)
		(fp_line
			(start -1.905 0.8636)
			(end 1.905 0.8636)
			(stroke
				(width 0.1524)
				(type default)
			)
			(layer "B.SilkS")
		)
		(fp_rect
			(start 1.524 0.7366)
			(end -1.524 -0.7366)
			(stroke
				(width 0)
				(type default)
			)
			(fill no)
			(layer "B.CrtYd")
		)
		(pad "1" smd rect
			(at -0.94996 0 270)
			(size 1.1176 1.3716)
			(layers "B.Cu" "B.Mask" "B.Paste")
			(net "P1V5_SUS_NODE1")
		)
		(pad "2" smd rect
			(at 0.94996 0 270)
			(size 1.1176 1.3716)
			(layers "B.Cu" "B.Mask" "B.Paste")
			(net "GND")
		)
	)
	(footprint ""
		(layer "B.Cu")
		(at 146.78152 -100.391468 -90)
		(property "Reference" ""
			(at 0 0 90)
			(layer "B.SilkS")
			(hide yes)
			(effects
				(font
					(size 1.27 1.27)
				)
				(justify mirror)
			)
		)
		(property "Value" ""
			(at 0 0 90)
			(layer "B.Fab")
			(effects
				(font
					(size 1.27 1.27)
				)
				(justify mirror)
			)
		)
		(duplicate_pad_numbers_are_jumpers no)
		(fp_poly
			(pts
				(arc
					(start 0 -1.4986)
					(mid 0 1.4986)
					(end 0 -1.4986)
				)
			)
			(stroke
				(width 0)
				(type default)
			)
			(fill no)
			(layer "B.CrtYd")
		)
		(pad "1" smd circle
			(at 0 0 90)
			(size 0.9906 0.9906)
			(layers "B.Cu" "B.Mask" "B.Paste")
			(net "Net_32")
		)
		(zone
			(layer "B.Cu")
			(hatch none 0.5)
			(connect_pads
				(clearance 0)
			)
			(min_thickness 0.25)
			(keepout
				(tracks not_allowed)
				(vias allowed)
				(pads allowed)
				(copperpour not_allowed)
				(footprints allowed)
			)
			(placement
				(enabled no)
				(sheetname "")
			)
			(fill
				(thermal_gap 0.5)
				(thermal_bridge_width 0.5)
				(island_removal_mode 0)
			)
			(polygon
				(pts
					(arc
						(start 148.40712 -100.391468)
						(mid 145.15592 -100.391468)
						(end 148.40712 -100.391468)
					)
				)
			)
		)
	)
	(footprint ""
		(layer "B.Cu")
		(at 171.846494 -123.401836 180)
		(property "Reference" "C784"
			(at 1.3335 3.452876 0)
			(unlocked yes)
			(layer "B.SilkS")
			(effects
				(font
					(size 0.7874 0.5842)
					(thickness 0.1524)
				)
				(justify mirror)
			)
		)
		(property "Value" ""
			(at 0 0 0)
			(layer "B.Fab")
			(effects
				(font
					(size 1.27 1.27)
				)
				(justify mirror)
			)
		)
		(duplicate_pad_numbers_are_jumpers no)
		(fp_line
			(start 1.2954 0.5842)
			(end 1.2954 -0.5842)
			(stroke
				(width 0.1524)
				(type default)
			)
			(layer "B.SilkS")
		)
		(fp_line
			(start 1.2954 -0.5842)
			(end -1.2954 -0.5842)
			(stroke
				(width 0.1524)
				(type default)
			)
			(layer "B.SilkS")
		)
		(fp_line
			(start 0 -0.5842)
			(end 0 0.5842)
			(stroke
				(width 0.1524)
				(type default)
			)
			(layer "B.SilkS")
		)
		(fp_line
			(start -1.2954 0.5842)
			(end 1.2954 0.5842)
			(stroke
				(width 0.1524)
				(type default)
			)
			(layer "B.SilkS")
		)
		(fp_line
			(start -1.2954 -0.5842)
			(end -1.2954 0.5842)
			(stroke
				(width 0.1524)
				(type default)
			)
			(layer "B.SilkS")
		)
		(fp_poly
			(pts
				(xy -0.8636 -0.4572) (xy -0.8636 -0.3556) (xy -1.143 -0.3556) (xy -1.143 0.3556) (xy -0.8636 0.3556)
				(xy -0.8636 0.4572) (xy 0.8636 0.4572) (xy 0.8636 0.3556) (xy 1.143 0.3556) (xy 1.143 -0.3556) (xy 0.8636 -0.3556)
				(xy 0.8636 -0.4572)
			)
			(stroke
				(width 0)
				(type default)
			)
			(fill no)
			(layer "B.CrtYd")
		)
		(fp_line
			(start 0.884936 0.504952)
			(end 0.884936 -0.504952)
			(stroke
				(width 0.1)
				(type default)
			)
			(layer "B.Fab")
		)
		(fp_line
			(start 0.884936 -0.504952)
			(end -0.884936 -0.504952)
			(stroke
				(width 0.1)
				(type default)
			)
			(layer "B.Fab")
		)
		(fp_line
			(start -0.884936 0.504952)
			(end 0.884936 0.504952)
			(stroke
				(width 0.1)
				(type default)
			)
			(layer "B.Fab")
		)
		(fp_line
			(start -0.884936 -0.504952)
			(end -0.884936 0.504952)
			(stroke
				(width 0.1)
				(type default)
			)
			(layer "B.Fab")
		)
		(pad "1" smd rect
			(at -0.7366 0 270)
			(size 0.7112 0.8128)
			(layers "B.Cu" "B.Mask" "B.Paste")
			(net "P3V3_STB_NODE1")
		)
		(pad "2" smd rect
			(at 0.7366 0 270)
			(size 0.7112 0.8128)
			(layers "B.Cu" "B.Mask" "B.Paste")
			(net "GND")
		)
	)
	(footprint ""
		(layer "B.Cu")
		(at 104.408224 -68.244466 180)
		(property "Reference" "R227"
			(at 4.704842 -0.713232 0)
			(unlocked yes)
			(layer "B.SilkS")
			(effects
				(font
					(size 0.7874 0.5842)
					(thickness 0.1524)
				)
				(justify left mirror)
			)
		)
		(property "Value" ""
			(at 0 0 0)
			(layer "B.Fab")
			(effects
				(font
					(size 1.27 1.27)
				)
				(justify mirror)
			)
		)
		(duplicate_pad_numbers_are_jumpers no)
		(fp_line
			(start 0.7874 0.4064)
			(end 0.7874 -0.4064)
			(stroke
				(width 0.1524)
				(type default)
			)
			(layer "B.SilkS")
		)
		(fp_line
			(start 0.7874 -0.4064)
			(end -0.7874 -0.4064)
			(stroke
				(width 0.1524)
				(type default)
			)
			(layer "B.SilkS")
		)
		(fp_line
			(start -0.7874 0.4064)
			(end 0.7874 0.4064)
			(stroke
				(width 0.1524)
				(type default)
			)
			(layer "B.SilkS")
		)
		(fp_line
			(start -0.7874 -0.4064)
			(end -0.7874 0.4064)
			(stroke
				(width 0.1524)
				(type default)
			)
			(layer "B.SilkS")
		)
		(fp_poly
			(pts
				(xy 0.508 0.2794) (xy 0.508 0.2286) (xy 0.635 0.2286) (xy 0.635 -0.254) (xy 0.5334 -0.254) (xy 0.5334 -0.2794)
				(xy -0.5334 -0.2794) (xy -0.5334 -0.254) (xy -0.635 -0.254) (xy -0.635 0.254) (xy -0.5334 0.254)
				(xy -0.5334 0.2794)
			)
			(stroke
				(width 0)
				(type default)
			)
			(fill no)
			(layer "B.CrtYd")
		)
		(pad "1" smd rect
			(at -0.40005 0)
			(size 0.4572 0.508)
			(layers "B.Cu" "B.Mask" "B.Paste")
			(net "XDP_CPU_NODE1_PWROK_STALL_L")
		)
		(pad "2" smd rect
			(at 0.40005 0)
			(size 0.4572 0.508)
			(layers "B.Cu" "B.Mask" "B.Paste")
			(net "GND")
		)
	)
	(footprint ""
		(layer "B.Cu")
		(at 68.81876 -188.126624 90)
		(property "Reference" "R926"
			(at 4.318254 -0.325882 270)
			(unlocked yes)
			(layer "B.SilkS")
			(effects
				(font
					(size 0.7874 0.5842)
					(thickness 0.1524)
				)
				(justify left mirror)
			)
		)
		(property "Value" ""
			(at 0 0 90)
			(layer "B.Fab")
			(effects
				(font
					(size 1.27 1.27)
				)
				(justify mirror)
			)
		)
		(duplicate_pad_numbers_are_jumpers no)
		(fp_line
			(start 0.7874 -0.4064)
			(end -0.7874 -0.4064)
			(stroke
				(width 0.1524)
				(type default)
			)
			(layer "B.SilkS")
		)
		(fp_line
			(start -0.7874 -0.4064)
			(end -0.7874 0.4064)
			(stroke
				(width 0.1524)
				(type default)
			)
			(layer "B.SilkS")
		)
		(fp_line
			(start 0.7874 0.4064)
			(end 0.7874 -0.4064)
			(stroke
				(width 0.1524)
				(type default)
			)
			(layer "B.SilkS")
		)
		(fp_line
			(start -0.7874 0.4064)
			(end 0.7874 0.4064)
			(stroke
				(width 0.1524)
				(type default)
			)
			(layer "B.SilkS")
		)
		(fp_poly
			(pts
				(xy 0.508 0.2794) (xy 0.508 0.2286) (xy 0.635 0.2286) (xy 0.635 -0.254) (xy 0.5334 -0.254) (xy 0.5334 -0.2794)
				(xy -0.5334 -0.2794) (xy -0.5334 -0.254) (xy -0.635 -0.254) (xy -0.635 0.254) (xy -0.5334 0.254)
				(xy -0.5334 0.2794)
			)
			(stroke
				(width 0)
				(type default)
			)
			(fill no)
			(layer "B.CrtYd")
		)
		(pad "1" smd rect
			(at -0.40005 0 270)
			(size 0.4572 0.508)
			(layers "B.Cu" "B.Mask" "B.Paste")
			(net "UART_T3_NODE4_RXD")
		)
		(pad "2" smd rect
			(at 0.40005 0 270)
			(size 0.4572 0.508)
			(layers "B.Cu" "B.Mask" "B.Paste")
			(net "UART_T3_NODE4_RXD_R")
		)
	)
	(footprint ""
		(layer "B.Cu")
		(at 165.87978 -158.608522)
		(property "Reference" "C443"
			(at 3.599942 -1.091946 0)
			(unlocked yes)
			(layer "B.SilkS")
			(effects
				(font
					(size 0.7874 0.5842)
					(thickness 0.1524)
				)
				(justify left mirror)
			)
		)
		(property "Value" ""
			(at 0 0 0)
			(layer "B.Fab")
			(effects
				(font
					(size 1.27 1.27)
				)
				(justify mirror)
			)
		)
		(duplicate_pad_numbers_are_jumpers no)
		(fp_line
			(start -0.7874 -0.4064)
			(end -0.7874 0.4064)
			(stroke
				(width 0.1524)
				(type default)
			)
			(layer "B.SilkS")
		)
		(fp_line
			(start -0.7874 0.4064)
			(end 0.7874 0.4064)
			(stroke
				(width 0.1524)
				(type default)
			)
			(layer "B.SilkS")
		)
		(fp_line
			(start 0 0.381)
			(end 0 -0.381)
			(stroke
				(width 0.1524)
				(type default)
			)
			(layer "B.SilkS")
		)
		(fp_line
			(start 0.7874 -0.4064)
			(end -0.7874 -0.4064)
			(stroke
				(width 0.1524)
				(type default)
			)
			(layer "B.SilkS")
		)
		(fp_line
			(start 0.7874 0.4064)
			(end 0.7874 -0.4064)
			(stroke
				(width 0.1524)
				(type default)
			)
			(layer "B.SilkS")
		)
		(fp_poly
			(pts
				(xy 0.5334 0.254) (xy 0.635 0.254) (xy 0.635 0.2286) (xy 0.635 -0.254) (xy 0.5334 -0.254) (xy 0.5334 -0.2794)
				(xy -0.5334 -0.2794) (xy -0.5334 -0.254) (xy -0.635 -0.254) (xy -0.635 0.254) (xy -0.5334 0.254)
				(xy -0.5334 0.2794) (xy 0.508 0.2794) (xy 0.5334 0.2794)
			)
			(stroke
				(width 0)
				(type default)
			)
			(fill no)
			(layer "B.CrtYd")
		)
		(pad "1" smd rect
			(at -0.40005 0 180)
			(size 0.4572 0.508)
			(layers "B.Cu" "B.Mask" "B.Paste")
			(net "P3V3_NODE1")
		)
		(pad "2" smd rect
			(at 0.40005 0 180)
			(size 0.4572 0.508)
			(layers "B.Cu" "B.Mask" "B.Paste")
			(net "GND")
		)
	)
	(footprint ""
		(layer "B.Cu")
		(at 151.572214 -62.075822 -90)
		(property "Reference" "C358"
			(at 2.829814 -6.163564 270)
			(unlocked yes)
			(layer "B.SilkS")
			(effects
				(font
					(size 0.7874 0.5842)
					(thickness 0.1524)
				)
				(justify left mirror)
			)
		)
		(property "Value" ""
			(at 0 0 90)
			(layer "B.Fab")
			(effects
				(font
					(size 1.27 1.27)
				)
				(justify mirror)
			)
		)
		(duplicate_pad_numbers_are_jumpers no)
		(fp_line
			(start -0.7874 0.4064)
			(end 0.7874 0.4064)
			(stroke
				(width 0.1524)
				(type default)
			)
			(layer "B.SilkS")
		)
		(fp_line
			(start 0.7874 0.4064)
			(end 0.7874 -0.4064)
			(stroke
				(width 0.1524)
				(type default)
			)
			(layer "B.SilkS")
		)
		(fp_line
			(start 0 0.381)
			(end 0 -0.381)
			(stroke
				(width 0.1524)
				(type default)
			)
			(layer "B.SilkS")
		)
		(fp_line
			(start -0.7874 -0.4064)
			(end -0.7874 0.4064)
			(stroke
				(width 0.1524)
				(type default)
			)
			(layer "B.SilkS")
		)
		(fp_line
			(start 0.7874 -0.4064)
			(end -0.7874 -0.4064)
			(stroke
				(width 0.1524)
				(type default)
			)
			(layer "B.SilkS")
		)
		(fp_poly
			(pts
				(xy 0.5334 0.254) (xy 0.635 0.254) (xy 0.635 0.2286) (xy 0.635 -0.254) (xy 0.5334 -0.254) (xy 0.5334 -0.2794)
				(xy -0.5334 -0.2794) (xy -0.5334 -0.254) (xy -0.635 -0.254) (xy -0.635 0.254) (xy -0.5334 0.254)
				(xy -0.5334 0.2794) (xy 0.508 0.2794) (xy 0.5334 0.2794)
			)
			(stroke
				(width 0)
				(type default)
			)
			(fill no)
			(layer "B.CrtYd")
		)
		(pad "1" smd rect
			(at -0.40005 0 90)
			(size 0.4572 0.508)
			(layers "B.Cu" "B.Mask" "B.Paste")
			(net "P1V8_SATA_VAA2_1_NODE1")
		)
		(pad "2" smd rect
			(at 0.40005 0 90)
			(size 0.4572 0.508)
			(layers "B.Cu" "B.Mask" "B.Paste")
			(net "GND")
		)
	)
	(footprint ""
		(layer "B.Cu")
		(at 65.38976 -188.126624 -90)
		(property "Reference" "C625"
			(at -4.318254 0.435864 270)
			(unlocked yes)
			(layer "B.SilkS")
			(effects
				(font
					(size 0.7874 0.5842)
					(thickness 0.1524)
				)
				(justify left mirror)
			)
		)
		(property "Value" ""
			(at 0 0 90)
			(layer "B.Fab")
			(effects
				(font
					(size 1.27 1.27)
				)
				(justify mirror)
			)
		)
		(duplicate_pad_numbers_are_jumpers no)
		(fp_line
			(start -0.7874 0.4064)
			(end 0.7874 0.4064)
			(stroke
				(width 0.1524)
				(type default)
			)
			(layer "B.SilkS")
		)
		(fp_line
			(start 0.7874 0.4064)
			(end 0.7874 -0.4064)
			(stroke
				(width 0.1524)
				(type default)
			)
			(layer "B.SilkS")
		)
		(fp_line
			(start 0 0.381)
			(end 0 -0.381)
			(stroke
				(width 0.1524)
				(type default)
			)
			(layer "B.SilkS")
		)
		(fp_line
			(start -0.7874 -0.4064)
			(end -0.7874 0.4064)
			(stroke
				(width 0.1524)
				(type default)
			)
			(layer "B.SilkS")
		)
		(fp_line
			(start 0.7874 -0.4064)
			(end -0.7874 -0.4064)
			(stroke
				(width 0.1524)
				(type default)
			)
			(layer "B.SilkS")
		)
		(fp_poly
			(pts
				(xy 0.5334 0.254) (xy 0.635 0.254) (xy 0.635 0.2286) (xy 0.635 -0.254) (xy 0.5334 -0.254) (xy 0.5334 -0.2794)
				(xy -0.5334 -0.2794) (xy -0.5334 -0.254) (xy -0.635 -0.254) (xy -0.635 0.254) (xy -0.5334 0.254)
				(xy -0.5334 0.2794) (xy 0.508 0.2794) (xy 0.5334 0.2794)
			)
			(stroke
				(width 0)
				(type default)
			)
			(fill no)
			(layer "B.CrtYd")
		)
		(pad "1" smd rect
			(at -0.40005 0 90)
			(size 0.4572 0.508)
			(layers "B.Cu" "B.Mask" "B.Paste")
			(net "T1_NODE2_EN_R")
		)
		(pad "2" smd rect
			(at 0.40005 0 90)
			(size 0.4572 0.508)
			(layers "B.Cu" "B.Mask" "B.Paste")
			(net "GND")
		)
	)
)
